(kicad_pcb
	(version 20260206)
	(generator "pcbnew")
	(generator_version "10.0")
	(general
		(thickness 1.6)
		(legacy_teardrops no)
	)
	(paper "A4")
	(title_block
		(title "panther-plus-userver — 13130-1b_20150205.brd")
		(comment 1 "Honey Badger (Wiwynn) / footprint 406 of 1509 (DIMM2), pads 170-176 of 210")
	)
	(layers
		(0 "F.Cu" signal "TOP")
		(4 "In1.Cu" signal "L2")
		(6 "In2.Cu" signal "L3")
		(8 "In3.Cu" signal "L4")
		(10 "In4.Cu" signal "L5")
		(12 "In5.Cu" signal "L6")
		(14 "In6.Cu" signal "L7")
		(16 "In7.Cu" signal "L8")
		(18 "In8.Cu" signal "L9")
		(20 "In9.Cu" signal "L10")
		(22 "In10.Cu" signal "L11")
		(2 "B.Cu" signal "BOTTOM")
		(9 "F.Adhes" user "F.Adhesive")
		(11 "B.Adhes" user "B.Adhesive")
		(13 "F.Paste" user "Package Geometry/Pastemask Top")
		(15 "B.Paste" user "Package Geometry/Pastemask Bottom")
		(5 "F.SilkS" user "Ref Des/Silkscreen Top")
		(7 "B.SilkS" user "Ref Des/Silkscreen Bottom")
		(1 "F.Mask" user "Board Geometry/Soldermask Top")
		(3 "B.Mask" user "Board Geometry/Soldermask Bottom")
		(17 "Dwgs.User" user "User.Drawings")
		(19 "Cmts.User" user "User.Comments")
		(21 "Eco1.User" user "User.Eco1")
		(23 "Eco2.User" user "User.Eco2")
		(25 "Edge.Cuts" user "Board Geometry/Outline")
		(27 "Margin" user)
		(31 "F.CrtYd" user "Package Geometry/Place Bound Top")
		(29 "B.CrtYd" user "Package Geometry/Place Bound Bottom")
		(35 "F.Fab" user "Ref Des/Assembly Top")
		(33 "B.Fab" user "Ref Des/Assembly Bottom")
	)
	(footprint ""
		(layer "F.Cu")
		(at 158.500064 -66.699892 180)
		(property "Reference" "DIMM2"
			(at 0 0 180)
			(layer "F.SilkS")
			(hide yes)
			(effects
				(font
					(size 1.27 1.27)
				)
			)
		)
		(property "Value" "DDR3-204P-174-COLAY-1-GP"
			(at -40.682164 -17.468088 180)
			(unlocked yes)
			(layer "F.Fab")
			(hide yes)
			(effects
				(font
					(size 1.016 1.016)
					(thickness 0.1524)
				)
			)
		)
		(property "Device Type" "AS0A626-H8SN-7H-COLAY-1"
			(at -40.682164 -18.992088 180)
			(unlocked yes)
			(layer "F.Fab")
			(hide yes)
			(effects
				(font
					(size 1.016 1.016)
					(thickness 0.1524)
				)
			)
		)
		(duplicate_pad_numbers_are_jumpers no)
		(pad "168" smd custom
			(at 20.850098 -4.106672 180)
			(size 0.1143 0.1143)
			(layers "F.Cu" "F.Mask" "F.Paste")
			(net "M_A_DQ49")
			(options
				(clearance outline)
				(anchor circle)
			)
			(primitives
				(gr_poly
					(pts
						(xy 0 0.9017) (xy -0.03175 0.89916) (xy -0.0635 0.889) (xy -0.09144 0.87376) (xy -0.11684 0.85344)
						(xy -0.13716 0.82804) (xy -0.1524 0.8001) (xy -0.16256 0.76835) (xy -0.1651 0.7366) (xy -0.1651 0.19685)
						(xy -0.17272 0.18923) (xy -0.17907 0.18034) (xy -0.18669 0.17145) (xy -0.19177 0.16256) (xy -0.19812 0.15367)
						(xy -0.20828 0.13335) (xy -0.21971 0.10287) (xy -0.22225 0.09271) (xy -0.22479 0.08128) (xy -0.22606 0.07112)
						(xy -0.2286 0.05969) (xy -0.2286 0.01651) (xy -0.22606 0.00508) (xy -0.22479 -0.00508) (xy -0.22225 -0.01651)
						(xy -0.21971 -0.02667) (xy -0.20828 -0.05715) (xy -0.19812 -0.07747) (xy -0.19177 -0.08636) (xy -0.18669 -0.09525)
						(xy -0.17907 -0.10414) (xy -0.17272 -0.11303) (xy -0.1651 -0.12065) (xy -0.1651 -0.7366) (xy -0.16256 -0.76835)
						(xy -0.1524 -0.8001) (xy -0.13716 -0.82804) (xy -0.11684 -0.85344) (xy -0.09144 -0.87376) (xy -0.0635 -0.889)
						(xy -0.03175 -0.89916) (xy 0 -0.9017) (xy 0.03175 -0.89916) (xy 0.0635 -0.889) (xy 0.09144 -0.87376)
						(xy 0.11684 -0.85344) (xy 0.13716 -0.82804) (xy 0.1524 -0.8001) (xy 0.16256 -0.76835) (xy 0.1651 -0.7366)
						(xy 0.1651 -0.11938) (xy 0.17272 -0.11176) (xy 0.19812 -0.0762) (xy 0.2032 -0.06604) (xy 0.20701 -0.05715)
						(xy 0.21209 -0.04699) (xy 0.2159 -0.03683) (xy 0.21844 -0.02667) (xy 0.22225 -0.01524) (xy 0.22352 -0.00508)
						(xy 0.22606 0.00508) (xy 0.22733 0.01651) (xy 0.22733 0.02667) (xy 0.2286 0.0381) (xy 0.22733 0.04953)
						(xy 0.22733 0.05969) (xy 0.22606 0.07112) (xy 0.22352 0.08128) (xy 0.22225 0.09144) (xy 0.21844 0.10287)
						(xy 0.2159 0.11303) (xy 0.21209 0.12319) (xy 0.20701 0.13335) (xy 0.2032 0.14224) (xy 0.19812 0.1524)
						(xy 0.17272 0.18796) (xy 0.1651 0.19558) (xy 0.1651 0.7366) (xy 0.16256 0.76835) (xy 0.1524 0.8001)
						(xy 0.13716 0.82804) (xy 0.11684 0.85344) (xy 0.09144 0.87376) (xy 0.0635 0.889) (xy 0.03175 0.89916)
					)
					(width 0)
					(fill yes)
				)
			)
		)
		(pad "169" smd custom
			(at 21.150072 4.106672 180)
			(size 0.1143 0.1143)
			(layers "F.Cu" "F.Mask" "F.Paste")
			(net "GND")
			(options
				(clearance outline)
				(anchor circle)
			)
			(primitives
				(gr_poly
					(pts
						(xy 0 0.9017) (xy -0.03175 0.89916) (xy -0.0635 0.889) (xy -0.09144 0.87376) (xy -0.11684 0.85344)
						(xy -0.13716 0.82804) (xy -0.1524 0.8001) (xy -0.16256 0.76835) (xy -0.1651 0.7366) (xy -0.1651 -0.13462)
						(xy -0.17272 -0.14224) (xy -0.19812 -0.1778) (xy -0.2032 -0.18796) (xy -0.20701 -0.19685) (xy -0.21209 -0.20701)
						(xy -0.2159 -0.21717) (xy -0.21844 -0.22733) (xy -0.22225 -0.23876) (xy -0.22352 -0.24892) (xy -0.22606 -0.25908)
						(xy -0.22733 -0.27051) (xy -0.22733 -0.28067) (xy -0.2286 -0.2921) (xy -0.22733 -0.30353) (xy -0.22733 -0.31369)
						(xy -0.22606 -0.32512) (xy -0.22352 -0.33528) (xy -0.22225 -0.34544) (xy -0.21844 -0.35687) (xy -0.2159 -0.36703)
						(xy -0.21209 -0.37719) (xy -0.20701 -0.38735) (xy -0.2032 -0.39624) (xy -0.19812 -0.4064) (xy -0.17272 -0.44196)
						(xy -0.1651 -0.44958) (xy -0.1651 -0.7366) (xy -0.16256 -0.76835) (xy -0.1524 -0.8001) (xy -0.13716 -0.82804)
						(xy -0.11684 -0.85344) (xy -0.09144 -0.87376) (xy -0.0635 -0.889) (xy -0.03175 -0.89916) (xy 0 -0.9017)
						(xy 0.03175 -0.89916) (xy 0.0635 -0.889) (xy 0.09144 -0.87376) (xy 0.11684 -0.85344) (xy 0.13716 -0.82804)
						(xy 0.1524 -0.8001) (xy 0.16256 -0.76835) (xy 0.1651 -0.7366) (xy 0.1651 -0.44958) (xy 0.17272 -0.44196)
						(xy 0.19812 -0.4064) (xy 0.2032 -0.39624) (xy 0.20701 -0.38735) (xy 0.21209 -0.37719) (xy 0.2159 -0.36703)
						(xy 0.21844 -0.35687) (xy 0.22225 -0.34544) (xy 0.22352 -0.33528) (xy 0.22606 -0.32512) (xy 0.22733 -0.31369)
						(xy 0.22733 -0.30353) (xy 0.2286 -0.2921) (xy 0.22733 -0.28067) (xy 0.22733 -0.27051) (xy 0.22606 -0.25908)
						(xy 0.22352 -0.24892) (xy 0.22225 -0.23876) (xy 0.21844 -0.22733) (xy 0.2159 -0.21717) (xy 0.21209 -0.20701)
						(xy 0.20701 -0.19685) (xy 0.2032 -0.18796) (xy 0.19812 -0.1778) (xy 0.17272 -0.14224) (xy 0.1651 -0.13462)
						(xy 0.1651 0.7366) (xy 0.16256 0.76835) (xy 0.1524 0.8001) (xy 0.13716 0.82804) (xy 0.11684 0.85344)
						(xy 0.09144 0.87376) (xy 0.0635 0.889) (xy 0.03175 0.89916)
					)
					(width 0)
					(fill yes)
				)
			)
		)
		(pad "170" smd custom
			(at 21.450046 -4.106672 180)
			(size 0.1143 0.1143)
			(layers "F.Cu" "F.Mask" "F.Paste")
			(net "GND")
			(options
				(clearance outline)
				(anchor circle)
			)
			(primitives
				(gr_poly
					(pts
						(xy 0 0.9017) (xy -0.03175 0.89916) (xy -0.0635 0.889) (xy -0.09144 0.87376) (xy -0.11684 0.85344)
						(xy -0.13716 0.82804) (xy -0.1524 0.8001) (xy -0.16256 0.76835) (xy -0.1651 0.7366) (xy -0.1651 0.44958)
						(xy -0.17272 0.44196) (xy -0.19812 0.4064) (xy -0.2032 0.39624) (xy -0.20701 0.38735) (xy -0.21209 0.37719)
						(xy -0.2159 0.36703) (xy -0.21844 0.35687) (xy -0.22225 0.34544) (xy -0.22352 0.33528) (xy -0.22606 0.32512)
						(xy -0.22733 0.31369) (xy -0.22733 0.30353) (xy -0.2286 0.2921) (xy -0.22733 0.28067) (xy -0.22733 0.27051)
						(xy -0.22606 0.25908) (xy -0.22352 0.24892) (xy -0.22225 0.23876) (xy -0.21844 0.22733) (xy -0.2159 0.21717)
						(xy -0.21209 0.20701) (xy -0.20701 0.19685) (xy -0.2032 0.18796) (xy -0.19812 0.1778) (xy -0.17272 0.14224)
						(xy -0.1651 0.13462) (xy -0.1651 -0.7366) (xy -0.16256 -0.76835) (xy -0.1524 -0.8001) (xy -0.13716 -0.82804)
						(xy -0.11684 -0.85344) (xy -0.09144 -0.87376) (xy -0.0635 -0.889) (xy -0.03175 -0.89916) (xy 0 -0.9017)
						(xy 0.03175 -0.89916) (xy 0.0635 -0.889) (xy 0.09144 -0.87376) (xy 0.11684 -0.85344) (xy 0.13716 -0.82804)
						(xy 0.1524 -0.8001) (xy 0.16256 -0.76835) (xy 0.1651 -0.7366) (xy 0.1651 0.13462) (xy 0.17272 0.14224)
						(xy 0.19812 0.1778) (xy 0.2032 0.18796) (xy 0.20701 0.19685) (xy 0.21209 0.20701) (xy 0.2159 0.21717)
						(xy 0.21844 0.22733) (xy 0.22225 0.23876) (xy 0.22352 0.24892) (xy 0.22606 0.25908) (xy 0.22733 0.27051)
						(xy 0.22733 0.28067) (xy 0.2286 0.2921) (xy 0.22733 0.30353) (xy 0.22733 0.31369) (xy 0.22606 0.32512)
						(xy 0.22352 0.33528) (xy 0.22225 0.34544) (xy 0.21844 0.35687) (xy 0.2159 0.36703) (xy 0.21209 0.37719)
						(xy 0.20701 0.38735) (xy 0.2032 0.39624) (xy 0.19812 0.4064) (xy 0.17272 0.44196) (xy 0.1651 0.44958)
						(xy 0.1651 0.7366) (xy 0.16256 0.76835) (xy 0.1524 0.8001) (xy 0.13716 0.82804) (xy 0.11684 0.85344)
						(xy 0.09144 0.87376) (xy 0.0635 0.889) (xy 0.03175 0.89916)
					)
					(width 0)
					(fill yes)
				)
			)
		)
		(pad "171" smd custom
			(at 21.75002 4.106672 180)
			(size 0.1143 0.1143)
			(layers "F.Cu" "F.Mask" "F.Paste")
			(net "M_A_DQS_DN6")
			(options
				(clearance outline)
				(anchor circle)
			)
			(primitives
				(gr_poly
					(pts
						(xy 0 0.9017) (xy -0.03175 0.89916) (xy -0.0635 0.889) (xy -0.09144 0.87376) (xy -0.11684 0.85344)
						(xy -0.13716 0.82804) (xy -0.1524 0.8001) (xy -0.16256 0.76835) (xy -0.1651 0.7366) (xy -0.1651 0.11938)
						(xy -0.17272 0.11176) (xy -0.19812 0.0762) (xy -0.2032 0.06604) (xy -0.20701 0.05715) (xy -0.21209 0.04699)
						(xy -0.2159 0.03683) (xy -0.21844 0.02667) (xy -0.22225 0.01524) (xy -0.22352 0.00508) (xy -0.22606 -0.00508)
						(xy -0.22733 -0.01651) (xy -0.22733 -0.02667) (xy -0.2286 -0.0381) (xy -0.22733 -0.04953) (xy -0.22733 -0.05969)
						(xy -0.22606 -0.07112) (xy -0.22352 -0.08128) (xy -0.22225 -0.09144) (xy -0.21844 -0.10287) (xy -0.2159 -0.11303)
						(xy -0.21209 -0.12319) (xy -0.20701 -0.13335) (xy -0.2032 -0.14224) (xy -0.19812 -0.1524) (xy -0.17272 -0.18796)
						(xy -0.1651 -0.19558) (xy -0.1651 -0.7366) (xy -0.16256 -0.76835) (xy -0.1524 -0.8001) (xy -0.13716 -0.82804)
						(xy -0.11684 -0.85344) (xy -0.09144 -0.87376) (xy -0.0635 -0.889) (xy -0.03175 -0.89916) (xy 0 -0.9017)
						(xy 0.03175 -0.89916) (xy 0.0635 -0.889) (xy 0.09144 -0.87376) (xy 0.11684 -0.85344) (xy 0.13716 -0.82804)
						(xy 0.1524 -0.8001) (xy 0.16256 -0.76835) (xy 0.1651 -0.7366) (xy 0.1651 -0.19685) (xy 0.17272 -0.18923)
						(xy 0.17907 -0.18034) (xy 0.18669 -0.17145) (xy 0.19177 -0.16256) (xy 0.19812 -0.15367) (xy 0.20828 -0.13335)
						(xy 0.21971 -0.10287) (xy 0.22225 -0.09271) (xy 0.22479 -0.08128) (xy 0.22606 -0.07112) (xy 0.2286 -0.05969)
						(xy 0.2286 -0.01651) (xy 0.22606 -0.00508) (xy 0.22479 0.00508) (xy 0.22225 0.01651) (xy 0.21971 0.02667)
						(xy 0.20828 0.05715) (xy 0.19812 0.07747) (xy 0.19177 0.08636) (xy 0.18669 0.09525) (xy 0.17907 0.10414)
						(xy 0.17272 0.11303) (xy 0.1651 0.12065) (xy 0.1651 0.7366) (xy 0.16256 0.76835) (xy 0.1524 0.8001)
						(xy 0.13716 0.82804) (xy 0.11684 0.85344) (xy 0.09144 0.87376) (xy 0.0635 0.889) (xy 0.03175 0.89916)
					)
					(width 0)
					(fill yes)
				)
			)
		)
		(pad "172" smd custom
			(at 22.049994 -4.106672 180)
			(size 0.1143 0.1143)
			(layers "F.Cu" "F.Mask" "F.Paste")
			(net "GND")
			(options
				(clearance outline)
				(anchor circle)
			)
			(primitives
				(gr_poly
					(pts
						(xy 0 0.9017) (xy -0.03175 0.89916) (xy -0.0635 0.889) (xy -0.09144 0.87376) (xy -0.11684 0.85344)
						(xy -0.13716 0.82804) (xy -0.1524 0.8001) (xy -0.16256 0.76835) (xy -0.1651 0.7366) (xy -0.1651 0.19685)
						(xy -0.17272 0.18923) (xy -0.17907 0.18034) (xy -0.18669 0.17145) (xy -0.19177 0.16256) (xy -0.19812 0.15367)
						(xy -0.20828 0.13335) (xy -0.21971 0.10287) (xy -0.22225 0.09271) (xy -0.22479 0.08128) (xy -0.22606 0.07112)
						(xy -0.2286 0.05969) (xy -0.2286 0.01651) (xy -0.22606 0.00508) (xy -0.22479 -0.00508) (xy -0.22225 -0.01651)
						(xy -0.21971 -0.02667) (xy -0.20828 -0.05715) (xy -0.19812 -0.07747) (xy -0.19177 -0.08636) (xy -0.18669 -0.09525)
						(xy -0.17907 -0.10414) (xy -0.17272 -0.11303) (xy -0.1651 -0.12065) (xy -0.1651 -0.7366) (xy -0.16256 -0.76835)
						(xy -0.1524 -0.8001) (xy -0.13716 -0.82804) (xy -0.11684 -0.85344) (xy -0.09144 -0.87376) (xy -0.0635 -0.889)
						(xy -0.03175 -0.89916) (xy 0 -0.9017) (xy 0.03175 -0.89916) (xy 0.0635 -0.889) (xy 0.09144 -0.87376)
						(xy 0.11684 -0.85344) (xy 0.13716 -0.82804) (xy 0.1524 -0.8001) (xy 0.16256 -0.76835) (xy 0.1651 -0.7366)
						(xy 0.1651 -0.11938) (xy 0.17272 -0.11176) (xy 0.19812 -0.0762) (xy 0.2032 -0.06604) (xy 0.20701 -0.05715)
						(xy 0.21209 -0.04699) (xy 0.2159 -0.03683) (xy 0.21844 -0.02667) (xy 0.22225 -0.01524) (xy 0.22352 -0.00508)
						(xy 0.22606 0.00508) (xy 0.22733 0.01651) (xy 0.22733 0.02667) (xy 0.2286 0.0381) (xy 0.22733 0.04953)
						(xy 0.22733 0.05969) (xy 0.22606 0.07112) (xy 0.22352 0.08128) (xy 0.22225 0.09144) (xy 0.21844 0.10287)
						(xy 0.2159 0.11303) (xy 0.21209 0.12319) (xy 0.20701 0.13335) (xy 0.2032 0.14224) (xy 0.19812 0.1524)
						(xy 0.17272 0.18796) (xy 0.1651 0.19558) (xy 0.1651 0.7366) (xy 0.16256 0.76835) (xy 0.1524 0.8001)
						(xy 0.13716 0.82804) (xy 0.11684 0.85344) (xy 0.09144 0.87376) (xy 0.0635 0.889) (xy 0.03175 0.89916)
					)
					(width 0)
					(fill yes)
				)
			)
		)
		(pad "173" smd custom
			(at 22.349968 4.106672 180)
			(size 0.1143 0.1143)
			(layers "F.Cu" "F.Mask" "F.Paste")
			(net "M_A_DQS_DP6")
			(options
				(clearance outline)
				(anchor circle)
			)
			(primitives
				(gr_poly
					(pts
						(xy 0 0.9017) (xy -0.03175 0.89916) (xy -0.0635 0.889) (xy -0.09144 0.87376) (xy -0.11684 0.85344)
						(xy -0.13716 0.82804) (xy -0.1524 0.8001) (xy -0.16256 0.76835) (xy -0.1651 0.7366) (xy -0.1651 -0.13462)
						(xy -0.17272 -0.14224) (xy -0.19812 -0.1778) (xy -0.2032 -0.18796) (xy -0.20701 -0.19685) (xy -0.21209 -0.20701)
						(xy -0.2159 -0.21717) (xy -0.21844 -0.22733) (xy -0.22225 -0.23876) (xy -0.22352 -0.24892) (xy -0.22606 -0.25908)
						(xy -0.22733 -0.27051) (xy -0.22733 -0.28067) (xy -0.2286 -0.2921) (xy -0.22733 -0.30353) (xy -0.22733 -0.31369)
						(xy -0.22606 -0.32512) (xy -0.22352 -0.33528) (xy -0.22225 -0.34544) (xy -0.21844 -0.35687) (xy -0.2159 -0.36703)
						(xy -0.21209 -0.37719) (xy -0.20701 -0.38735) (xy -0.2032 -0.39624) (xy -0.19812 -0.4064) (xy -0.17272 -0.44196)
						(xy -0.1651 -0.44958) (xy -0.1651 -0.7366) (xy -0.16256 -0.76835) (xy -0.1524 -0.8001) (xy -0.13716 -0.82804)
						(xy -0.11684 -0.85344) (xy -0.09144 -0.87376) (xy -0.0635 -0.889) (xy -0.03175 -0.89916) (xy 0 -0.9017)
						(xy 0.03175 -0.89916) (xy 0.0635 -0.889) (xy 0.09144 -0.87376) (xy 0.11684 -0.85344) (xy 0.13716 -0.82804)
						(xy 0.1524 -0.8001) (xy 0.16256 -0.76835) (xy 0.1651 -0.7366) (xy 0.1651 -0.44958) (xy 0.17272 -0.44196)
						(xy 0.19812 -0.4064) (xy 0.2032 -0.39624) (xy 0.20701 -0.38735) (xy 0.21209 -0.37719) (xy 0.2159 -0.36703)
						(xy 0.21844 -0.35687) (xy 0.22225 -0.34544) (xy 0.22352 -0.33528) (xy 0.22606 -0.32512) (xy 0.22733 -0.31369)
						(xy 0.22733 -0.30353) (xy 0.2286 -0.2921) (xy 0.22733 -0.28067) (xy 0.22733 -0.27051) (xy 0.22606 -0.25908)
						(xy 0.22352 -0.24892) (xy 0.22225 -0.23876) (xy 0.21844 -0.22733) (xy 0.2159 -0.21717) (xy 0.21209 -0.20701)
						(xy 0.20701 -0.19685) (xy 0.2032 -0.18796) (xy 0.19812 -0.1778) (xy 0.17272 -0.14224) (xy 0.1651 -0.13462)
						(xy 0.1651 0.7366) (xy 0.16256 0.76835) (xy 0.1524 0.8001) (xy 0.13716 0.82804) (xy 0.11684 0.85344)
						(xy 0.09144 0.87376) (xy 0.0635 0.889) (xy 0.03175 0.89916)
					)
					(width 0)
					(fill yes)
				)
			)
		)
		(pad "174" smd custom
			(at 22.649942 -4.106672 180)
			(size 0.1143 0.1143)
			(layers "F.Cu" "F.Mask" "F.Paste")
			(net "M_A_DQ50")
			(options
				(clearance outline)
				(anchor circle)
			)
			(primitives
				(gr_poly
					(pts
						(xy 0 0.9017) (xy -0.03175 0.89916) (xy -0.0635 0.889) (xy -0.09144 0.87376) (xy -0.11684 0.85344)
						(xy -0.13716 0.82804) (xy -0.1524 0.8001) (xy -0.16256 0.76835) (xy -0.1651 0.7366) (xy -0.1651 0.44958)
						(xy -0.17272 0.44196) (xy -0.19812 0.4064) (xy -0.2032 0.39624) (xy -0.20701 0.38735) (xy -0.21209 0.37719)
						(xy -0.2159 0.36703) (xy -0.21844 0.35687) (xy -0.22225 0.34544) (xy -0.22352 0.33528) (xy -0.22606 0.32512)
						(xy -0.22733 0.31369) (xy -0.22733 0.30353) (xy -0.2286 0.2921) (xy -0.22733 0.28067) (xy -0.22733 0.27051)
						(xy -0.22606 0.25908) (xy -0.22352 0.24892) (xy -0.22225 0.23876) (xy -0.21844 0.22733) (xy -0.2159 0.21717)
						(xy -0.21209 0.20701) (xy -0.20701 0.19685) (xy -0.2032 0.18796) (xy -0.19812 0.1778) (xy -0.17272 0.14224)
						(xy -0.1651 0.13462) (xy -0.1651 -0.7366) (xy -0.16256 -0.76835) (xy -0.1524 -0.8001) (xy -0.13716 -0.82804)
						(xy -0.11684 -0.85344) (xy -0.09144 -0.87376) (xy -0.0635 -0.889) (xy -0.03175 -0.89916) (xy 0 -0.9017)
						(xy 0.03175 -0.89916) (xy 0.0635 -0.889) (xy 0.09144 -0.87376) (xy 0.11684 -0.85344) (xy 0.13716 -0.82804)
						(xy 0.1524 -0.8001) (xy 0.16256 -0.76835) (xy 0.1651 -0.7366) (xy 0.1651 0.13462) (xy 0.17272 0.14224)
						(xy 0.19812 0.1778) (xy 0.2032 0.18796) (xy 0.20701 0.19685) (xy 0.21209 0.20701) (xy 0.2159 0.21717)
						(xy 0.21844 0.22733) (xy 0.22225 0.23876) (xy 0.22352 0.24892) (xy 0.22606 0.25908) (xy 0.22733 0.27051)
						(xy 0.22733 0.28067) (xy 0.2286 0.2921) (xy 0.22733 0.30353) (xy 0.22733 0.31369) (xy 0.22606 0.32512)
						(xy 0.22352 0.33528) (xy 0.22225 0.34544) (xy 0.21844 0.35687) (xy 0.2159 0.36703) (xy 0.21209 0.37719)
						(xy 0.20701 0.38735) (xy 0.2032 0.39624) (xy 0.19812 0.4064) (xy 0.17272 0.44196) (xy 0.1651 0.44958)
						(xy 0.1651 0.7366) (xy 0.16256 0.76835) (xy 0.1524 0.8001) (xy 0.13716 0.82804) (xy 0.11684 0.85344)
						(xy 0.09144 0.87376) (xy 0.0635 0.889) (xy 0.03175 0.89916)
					)
					(width 0)
					(fill yes)
				)
			)
		)
	)
)
